# S9S_MB_2U (Grand Teton) — schematic netlist excerpt (pin names and nets, part order shuffled) for the footprints in the layout excerpt that follows; sources: Cadence DE-HDL packaged netlist, KiCad conversion of 03242023_DA0F0TMBIJ0_F0T_Motherboard_J_brd_V01_OCP.brd

C162  Q_CAP_DIFFBUS  DIFF BUS_0.22UF 6.3V 20% X6S  pkg C0201  page 178 : \1\ = DMI_CPU0_PCH_RX_C_DP<4> ; \2\ = DMI_CPU0_PCH_RX_DP<4>
C1191  Q_CAP  22UF 6.3V 20% X6S  pkg C0603  page 189 : A = P3V3_AUX ; B = GND
R903  Q_RES  33.2 1% CHIP  pkg 0402LF  page 114 : A = PWRGD_CHF_CPU1_DIMM1 ; B = PWRGD_FAIL_CPU1_EF

(kicad_pcb
	(version 20260206)
	(generator "pcbnew")
	(generator_version "10.0")
	(general
		(thickness 1.6)
		(legacy_teardrops no)
	)
	(paper "A4")
	(title_block
		(title "03242023_DA0F0TMBIJ0_F0T_Motherboard_J_brd_V01_OCP.brd")
		(comment 1 "Grand Teton / footprints 5694-5696 of 6105")
	)
	(layers
		(0 "F.Cu" signal "TOP")
		(4 "In1.Cu" signal "GND")
		(6 "In2.Cu" signal "IN1")
		(8 "In3.Cu" signal "GND1")
		(10 "In4.Cu" signal "IN2")
		(12 "In5.Cu" signal "GND2")
		(14 "In6.Cu" signal "IN3")
		(16 "In7.Cu" signal "GND3")
		(18 "In8.Cu" signal "VCC")
		(20 "In9.Cu" signal "VCC1")
		(22 "In10.Cu" signal "GND4")
		(24 "In11.Cu" signal "IN4")
		(26 "In12.Cu" signal "GND5")
		(28 "In13.Cu" signal "IN5")
		(30 "In14.Cu" signal "GND6")
		(32 "In15.Cu" signal "IN6")
		(34 "In16.Cu" signal "GND7")
		(2 "B.Cu" signal "BOTTOM")
		(9 "F.Adhes" user "F.Adhesive")
		(11 "B.Adhes" user "B.Adhesive")
		(13 "F.Paste" user "Package Geometry/Pastemask Top")
		(15 "B.Paste" user "Package Geometry/Pastemask Bottom")
		(5 "F.SilkS" user "Ref Des/Silkscreen Top")
		(7 "B.SilkS" user "Ref Des/Silkscreen Bottom")
		(1 "F.Mask" user "Board Geometry/Soldermask Top")
		(3 "B.Mask" user "Board Geometry/Soldermask Bottom")
		(17 "Dwgs.User" user "User.Drawings")
		(19 "Cmts.User" user "User.Comments")
		(21 "Eco1.User" user "User.Eco1")
		(23 "Eco2.User" user "User.Eco2")
		(25 "Edge.Cuts" user "Board Geometry/Outline")
		(27 "Margin" user)
		(31 "F.CrtYd" user "Package Geometry/Place Bound Top")
		(29 "B.CrtYd" user "Package Geometry/Place Bound Bottom")
		(35 "F.Fab" user "Ref Des/Assembly Top")
		(33 "B.Fab" user "Ref Des/Assembly Bottom")
	)
	(footprint ""
		(layer "B.Cu")
		(at 343.840308 -62.056264 90)
		(property "Reference" "C162"
			(at 0 0 90)
			(layer "B.SilkS")
			(hide yes)
			(effects
				(font
					(size 1.27 1.27)
				)
				(justify mirror)
			)
		)
		(property "Value" ""
			(at 0 0 90)
			(layer "B.Fab")
			(effects
				(font
					(size 1.27 1.27)
				)
				(justify mirror)
			)
		)
		(duplicate_pad_numbers_are_jumpers no)
		(fp_line
			(start 0.299974 -0.150114)
			(end -0.299974 -0.150114)
			(stroke
				(width 0.1)
				(type default)
			)
			(layer "B.Fab")
		)
		(fp_line
			(start -0.299974 -0.150114)
			(end -0.299974 0.150114)
			(stroke
				(width 0.1)
				(type default)
			)
			(layer "B.Fab")
		)
		(fp_line
			(start 0.299974 0.150114)
			(end 0.299974 -0.150114)
			(stroke
				(width 0.1)
				(type default)
			)
			(layer "B.Fab")
		)
		(fp_line
			(start -0.299974 0.150114)
			(end 0.299974 0.150114)
			(stroke
				(width 0.1)
				(type default)
			)
			(layer "B.Fab")
		)
		(pad "1" smd rect
			(at 0.2667 0 270)
			(size 0.3048 0.381)
			(layers "B.Cu" "B.Mask" "B.Paste")
			(net "DMI_CPU0_PCH_RX_C_DP<4>")
		)
		(pad "2" smd rect
			(at -0.2667 0 270)
			(size 0.3048 0.381)
			(layers "B.Cu" "B.Mask" "B.Paste")
			(net "DMI_CPU0_PCH_RX_DP<4>")
		)
	)
	(footprint ""
		(layer "B.Cu")
		(at 325.66483 -66.840354 -90)
		(property "Reference" "C1191"
			(at 0 0 90)
			(layer "B.SilkS")
			(hide yes)
			(effects
				(font
					(size 1.27 1.27)
				)
				(justify mirror)
			)
		)
		(property "Value" ""
			(at 0 0 90)
			(layer "B.Fab")
			(effects
				(font
					(size 1.27 1.27)
				)
				(justify mirror)
			)
		)
		(duplicate_pad_numbers_are_jumpers no)
		(fp_line
			(start -1.2954 0.5842)
			(end 1.2954 0.5842)
			(stroke
				(width 0.1524)
				(type default)
			)
			(layer "B.SilkS")
		)
		(fp_line
			(start 1.2954 0.5842)
			(end 1.2954 -0.5842)
			(stroke
				(width 0.1524)
				(type default)
			)
			(layer "B.SilkS")
		)
		(fp_line
			(start -1.2954 -0.5842)
			(end -1.2954 0.5842)
			(stroke
				(width 0.1524)
				(type default)
			)
			(layer "B.SilkS")
		)
		(fp_line
			(start 0 -0.5842)
			(end 0 0.5842)
			(stroke
				(width 0.1524)
				(type default)
			)
			(layer "B.SilkS")
		)
		(fp_line
			(start 1.2954 -0.5842)
			(end -1.2954 -0.5842)
			(stroke
				(width 0.1524)
				(type default)
			)
			(layer "B.SilkS")
		)
		(fp_line
			(start -0.8636 0.4572)
			(end 0.8636 0.4572)
			(stroke
				(width 0.1)
				(type default)
			)
			(layer "B.Fab")
		)
		(fp_line
			(start 0.8636 0.4572)
			(end 0.8636 0.4064)
			(stroke
				(width 0.1)
				(type default)
			)
			(layer "B.Fab")
		)
		(fp_line
			(start -1.1938 0.4064)
			(end -0.8636 0.4064)
			(stroke
				(width 0.1)
				(type default)
			)
			(layer "B.Fab")
		)
		(fp_line
			(start -0.8636 0.4064)
			(end -0.8636 0.4572)
			(stroke
				(width 0.1)
				(type default)
			)
			(layer "B.Fab")
		)
		(fp_line
			(start 0.8636 0.4064)
			(end 1.1938 0.4064)
			(stroke
				(width 0.1)
				(type default)
			)
			(layer "B.Fab")
		)
		(fp_line
			(start 1.1938 0.4064)
			(end 1.1938 -0.4064)
			(stroke
				(width 0.1)
				(type default)
			)
			(layer "B.Fab")
		)
		(fp_line
			(start -1.1938 -0.4064)
			(end -1.1938 0.4064)
			(stroke
				(width 0.1)
				(type default)
			)
			(layer "B.Fab")
		)
		(fp_line
			(start -0.8636 -0.4064)
			(end -1.1938 -0.4064)
			(stroke
				(width 0.1)
				(type default)
			)
			(layer "B.Fab")
		)
		(fp_line
			(start 0.8636 -0.4064)
			(end 0.8636 -0.4572)
			(stroke
				(width 0.1)
				(type default)
			)
			(layer "B.Fab")
		)
		(fp_line
			(start 1.1938 -0.4064)
			(end 0.8636 -0.4064)
			(stroke
				(width 0.1)
				(type default)
			)
			(layer "B.Fab")
		)
		(fp_line
			(start -0.8636 -0.4572)
			(end -0.8636 -0.4064)
			(stroke
				(width 0.1)
				(type default)
			)
			(layer "B.Fab")
		)
		(fp_line
			(start 0.8636 -0.4572)
			(end -0.8636 -0.4572)
			(stroke
				(width 0.1)
				(type default)
			)
			(layer "B.Fab")
		)
		(pad "1" smd rect
			(at 0.7366 0 180)
			(size 0.7112 0.8128)
			(layers "B.Cu" "B.Mask" "B.Paste")
			(net "P3V3_AUX")
		)
		(pad "2" smd rect
			(at -0.7366 0 180)
			(size 0.7112 0.8128)
			(layers "B.Cu" "B.Mask" "B.Paste")
			(net "GND")
		)
	)
	(footprint ""
		(layer "B.Cu")
		(at 185.503312 -319.023492 90)
		(property "Reference" "R903"
			(at 0 0 90)
			(layer "B.SilkS")
			(hide yes)
			(effects
				(font
					(size 1.27 1.27)
				)
				(justify mirror)
			)
		)
		(property "Value" ""
			(at 0 0 90)
			(layer "B.Fab")
			(effects
				(font
					(size 1.27 1.27)
				)
				(justify mirror)
			)
		)
		(duplicate_pad_numbers_are_jumpers no)
		(fp_line
			(start 0.7874 -0.4064)
			(end -0.7874 -0.4064)
			(stroke
				(width 0.1524)
				(type default)
			)
			(layer "B.SilkS")
		)
		(fp_line
			(start -0.7874 -0.4064)
			(end -0.7874 0.4064)
			(stroke
				(width 0.1524)
				(type default)
			)
			(layer "B.SilkS")
		)
		(fp_line
			(start 0.7874 0.4064)
			(end 0.7874 -0.4064)
			(stroke
				(width 0.1524)
				(type default)
			)
			(layer "B.SilkS")
		)
		(fp_line
			(start -0.7874 0.4064)
			(end 0.7874 0.4064)
			(stroke
				(width 0.1524)
				(type default)
			)
			(layer "B.SilkS")
		)
		(fp_line
			(start 0.67945 -0.305054)
			(end 0.12065 -0.305054)
			(stroke
				(width 0.1)
				(type default)
			)
			(layer "B.Fab")
		)
		(fp_line
			(start 0.12065 -0.305054)
			(end 0.12065 -0.2794)
			(stroke
				(width 0.1)
				(type default)
			)
			(layer "B.Fab")
		)
		(fp_line
			(start -0.12065 -0.3048)
			(end -0.67945 -0.3048)
			(stroke
				(width 0.1)
				(type default)
			)
			(layer "B.Fab")
		)
		(fp_line
			(start -0.67945 -0.3048)
			(end -0.67945 0.3048)
			(stroke
				(width 0.1)
				(type default)
			)
			(layer "B.Fab")
		)
		(fp_line
			(start 0.12065 -0.2794)
			(end -0.12065 -0.2794)
			(stroke
				(width 0.1)
				(type default)
			)
			(layer "B.Fab")
		)
		(fp_line
			(start -0.12065 -0.2794)
			(end -0.12065 -0.3048)
			(stroke
				(width 0.1)
				(type default)
			)
			(layer "B.Fab")
		)
		(fp_line
			(start 0.12065 0.2794)
			(end 0.12065 0.3048)
			(stroke
				(width 0.1)
				(type default)
			)
			(layer "B.Fab")
		)
		(fp_line
			(start -0.120396 0.2794)
			(end 0.12065 0.2794)
			(stroke
				(width 0.1)
				(type default)
			)
			(layer "B.Fab")
		)
		(fp_line
			(start 0.67945 0.3048)
			(end 0.67945 -0.305054)
			(stroke
				(width 0.1)
				(type default)
			)
			(layer "B.Fab")
		)
		(fp_line
			(start 0.12065 0.3048)
			(end 0.67945 0.3048)
			(stroke
				(width 0.1)
				(type default)
			)
			(layer "B.Fab")
		)
		(fp_line
			(start -0.120396 0.3048)
			(end -0.120396 0.2794)
			(stroke
				(width 0.1)
				(type default)
			)
			(layer "B.Fab")
		)
		(fp_line
			(start -0.67945 0.3048)
			(end -0.120396 0.3048)
			(stroke
				(width 0.1)
				(type default)
			)
			(layer "B.Fab")
		)
		(pad "1" smd circle
			(at 0.40005 0 270)
			(size 0 0)
			(layers "B.Cu" "B.Mask" "B.Paste")
			(net "PWRGD_CHF_CPU1_DIMM1")
		)
		(pad "2" smd circle
			(at -0.40005 0 270)
			(size 0 0)
			(layers "B.Cu" "B.Mask" "B.Paste")
			(net "PWRGD_FAIL_CPU1_EF")
		)
	)
)
